# S9S_MB_2U (Grand Teton) — schematic netlist excerpt (pin names and nets, part order shuffled) for the footprints in the layout excerpt that follows; sources: Cadence DE-HDL packaged netlist, KiCad conversion of 03242023_DA0F0TMBIJ0_F0T_Motherboard_J_brd_V01_OCP.brd

U1_BL  TP  NA  pkg TP_BOM ONLY  page 312 : TP = NC
R2394  Q_RES  0 5% CHIP  pkg 0402LF  page 274 : A = FM_PVCCFA_EHV_CPU0_EN ; B = PVCCFA_EHV_CPU0_EN_R
R2843  Q_RES  4.7K 1% CHIP  pkg 0402LF  page 250 : A = P3V3_ADC ; B = GND
C1553  Q_CAP_DIFFBUS  DIFF BUS_0.22UF 6.3V 20% X6S  pkg C0201  page 175 : \1\ = P5E_CPU0_PE4_TX_C_DP<13> ; \2\ = P5E_CPU0_PE4_TX_DP<13>

(kicad_pcb
	(version 20260206)
	(generator "pcbnew")
	(generator_version "10.0")
	(general
		(thickness 1.6)
		(legacy_teardrops no)
	)
	(paper "A4")
	(title_block
		(title "03242023_DA0F0TMBIJ0_F0T_Motherboard_J_brd_V01_OCP.brd")
		(comment 1 "Grand Teton / footprints 4025-4028 of 6105")
	)
	(layers
		(0 "F.Cu" signal "TOP")
		(4 "In1.Cu" signal "GND")
		(6 "In2.Cu" signal "IN1")
		(8 "In3.Cu" signal "GND1")
		(10 "In4.Cu" signal "IN2")
		(12 "In5.Cu" signal "GND2")
		(14 "In6.Cu" signal "IN3")
		(16 "In7.Cu" signal "GND3")
		(18 "In8.Cu" signal "VCC")
		(20 "In9.Cu" signal "VCC1")
		(22 "In10.Cu" signal "GND4")
		(24 "In11.Cu" signal "IN4")
		(26 "In12.Cu" signal "GND5")
		(28 "In13.Cu" signal "IN5")
		(30 "In14.Cu" signal "GND6")
		(32 "In15.Cu" signal "IN6")
		(34 "In16.Cu" signal "GND7")
		(2 "B.Cu" signal "BOTTOM")
		(9 "F.Adhes" user "F.Adhesive")
		(11 "B.Adhes" user "B.Adhesive")
		(13 "F.Paste" user "Package Geometry/Pastemask Top")
		(15 "B.Paste" user "Package Geometry/Pastemask Bottom")
		(5 "F.SilkS" user "Ref Des/Silkscreen Top")
		(7 "B.SilkS" user "Ref Des/Silkscreen Bottom")
		(1 "F.Mask" user "Board Geometry/Soldermask Top")
		(3 "B.Mask" user "Board Geometry/Soldermask Bottom")
		(17 "Dwgs.User" user "User.Drawings")
		(19 "Cmts.User" user "User.Comments")
		(21 "Eco1.User" user "User.Eco1")
		(23 "Eco2.User" user "User.Eco2")
		(25 "Edge.Cuts" user "Board Geometry/Outline")
		(27 "Margin" user)
		(31 "F.CrtYd" user "Package Geometry/Place Bound Top")
		(29 "B.CrtYd" user "Package Geometry/Place Bound Bottom")
		(35 "F.Fab" user "Ref Des/Assembly Top")
		(33 "B.Fab" user "Ref Des/Assembly Bottom")
	)
	(footprint ""
		(layer "F.Cu")
		(at 344.691208 -402.371052 -90)
		(property "Reference" "C1553"
			(at 0 0 270)
			(layer "F.SilkS")
			(hide yes)
			(effects
				(font
					(size 1.27 1.27)
				)
			)
		)
		(property "Value" ""
			(at 0 0 270)
			(layer "F.Fab")
			(effects
				(font
					(size 1.27 1.27)
				)
			)
		)
		(duplicate_pad_numbers_are_jumpers no)
		(fp_line
			(start -0.299974 0.150114)
			(end -0.299974 -0.150114)
			(stroke
				(width 0.1)
				(type default)
			)
			(layer "F.Fab")
		)
		(fp_line
			(start 0.299974 0.150114)
			(end -0.299974 0.150114)
			(stroke
				(width 0.1)
				(type default)
			)
			(layer "F.Fab")
		)
		(fp_line
			(start -0.299974 -0.150114)
			(end 0.299974 -0.150114)
			(stroke
				(width 0.1)
				(type default)
			)
			(layer "F.Fab")
		)
		(fp_line
			(start 0.299974 -0.150114)
			(end 0.299974 0.150114)
			(stroke
				(width 0.1)
				(type default)
			)
			(layer "F.Fab")
		)
		(pad "1" smd rect
			(at -0.2667 0 270)
			(size 0.3048 0.381)
			(layers "F.Cu" "F.Mask" "F.Paste")
			(net "P5E_CPU0_PE4_TX_C_DP<13>")
		)
		(pad "2" smd rect
			(at 0.2667 0 270)
			(size 0.3048 0.381)
			(layers "F.Cu" "F.Mask" "F.Paste")
			(net "P5E_CPU0_PE4_TX_DP<13>")
		)
	)
	(footprint ""
		(layer "F.Cu")
		(at 44.169584 -108.047282)
		(property "Reference" "R2843"
			(at 0 0 0)
			(layer "F.SilkS")
			(hide yes)
			(effects
				(font
					(size 1.27 1.27)
				)
			)
		)
		(property "Value" ""
			(at 0 0 0)
			(layer "F.Fab")
			(effects
				(font
					(size 1.27 1.27)
				)
			)
		)
		(duplicate_pad_numbers_are_jumpers no)
		(fp_line
			(start -0.7874 -0.4064)
			(end 0.7874 -0.4064)
			(stroke
				(width 0.1524)
				(type default)
			)
			(layer "F.SilkS")
		)
		(fp_line
			(start -0.7874 0.4064)
			(end -0.7874 -0.4064)
			(stroke
				(width 0.1524)
				(type default)
			)
			(layer "F.SilkS")
		)
		(fp_line
			(start 0.7874 -0.4064)
			(end 0.7874 0.4064)
			(stroke
				(width 0.1524)
				(type default)
			)
			(layer "F.SilkS")
		)
		(fp_line
			(start 0.7874 0.4064)
			(end -0.7874 0.4064)
			(stroke
				(width 0.1524)
				(type default)
			)
			(layer "F.SilkS")
		)
		(fp_line
			(start -0.67945 -0.305054)
			(end -0.12065 -0.305054)
			(stroke
				(width 0.1)
				(type default)
			)
			(layer "F.Fab")
		)
		(fp_line
			(start -0.67945 0.3048)
			(end -0.67945 -0.305054)
			(stroke
				(width 0.1)
				(type default)
			)
			(layer "F.Fab")
		)
		(fp_line
			(start -0.12065 -0.305054)
			(end -0.12065 -0.2794)
			(stroke
				(width 0.1)
				(type default)
			)
			(layer "F.Fab")
		)
		(fp_line
			(start -0.12065 -0.2794)
			(end 0.12065 -0.2794)
			(stroke
				(width 0.1)
				(type default)
			)
			(layer "F.Fab")
		)
		(fp_line
			(start -0.12065 0.2794)
			(end -0.12065 0.3048)
			(stroke
				(width 0.1)
				(type default)
			)
			(layer "F.Fab")
		)
		(fp_line
			(start -0.12065 0.3048)
			(end -0.67945 0.3048)
			(stroke
				(width 0.1)
				(type default)
			)
			(layer "F.Fab")
		)
		(fp_line
			(start 0.120396 0.2794)
			(end -0.12065 0.2794)
			(stroke
				(width 0.1)
				(type default)
			)
			(layer "F.Fab")
		)
		(fp_line
			(start 0.120396 0.3048)
			(end 0.120396 0.2794)
			(stroke
				(width 0.1)
				(type default)
			)
			(layer "F.Fab")
		)
		(fp_line
			(start 0.12065 -0.3048)
			(end 0.67945 -0.3048)
			(stroke
				(width 0.1)
				(type default)
			)
			(layer "F.Fab")
		)
		(fp_line
			(start 0.12065 -0.2794)
			(end 0.12065 -0.3048)
			(stroke
				(width 0.1)
				(type default)
			)
			(layer "F.Fab")
		)
		(fp_line
			(start 0.67945 -0.3048)
			(end 0.67945 0.3048)
			(stroke
				(width 0.1)
				(type default)
			)
			(layer "F.Fab")
		)
		(fp_line
			(start 0.67945 0.3048)
			(end 0.120396 0.3048)
			(stroke
				(width 0.1)
				(type default)
			)
			(layer "F.Fab")
		)
		(pad "1" smd circle
			(at -0.40005 0)
			(size 0 0)
			(layers "F.Cu" "F.Mask" "F.Paste")
			(net "P3V3_ADC")
		)
		(pad "2" smd circle
			(at 0.40005 0)
			(size 0 0)
			(layers "F.Cu" "F.Mask" "F.Paste")
			(net "GND")
		)
	)
	(footprint ""
		(layer "F.Cu")
		(at 488.85729 -470.49817)
		(property "Reference" "U1_BL"
			(at -1.46685 -1.175258 0)
			(unlocked yes)
			(layer "F.SilkS")
			(effects
				(font
					(size 0.7874 0.5842)
					(thickness 0.1524)
				)
				(justify left)
			)
		)
		(property "Value" ""
			(at 0 0 0)
			(layer "F.Fab")
			(effects
				(font
					(size 1.27 1.27)
				)
			)
		)
		(duplicate_pad_numbers_are_jumpers no)
		(pad "1" smd circle
			(at 0 0)
			(size 0.762 0.762)
			(layers "F.Cu" "F.Mask" "F.Paste")
			(net "Net_8488")
		)
	)
	(footprint ""
		(layer "F.Cu")
		(at 430.600104 -140.595858 180)
		(property "Reference" "R2394"
			(at 0 0 180)
			(layer "F.SilkS")
			(hide yes)
			(effects
				(font
					(size 1.27 1.27)
				)
			)
		)
		(property "Value" ""
			(at 0 0 180)
			(layer "F.Fab")
			(effects
				(font
					(size 1.27 1.27)
				)
			)
		)
		(duplicate_pad_numbers_are_jumpers no)
		(fp_line
			(start 0.7874 0.4064)
			(end -0.7874 0.4064)
			(stroke
				(width 0.1524)
				(type default)
			)
			(layer "F.SilkS")
		)
		(fp_line
			(start 0.7874 -0.4064)
			(end 0.7874 0.4064)
			(stroke
				(width 0.1524)
				(type default)
			)
			(layer "F.SilkS")
		)
		(fp_line
			(start -0.7874 0.4064)
			(end -0.7874 -0.4064)
			(stroke
				(width 0.1524)
				(type default)
			)
			(layer "F.SilkS")
		)
		(fp_line
			(start -0.7874 -0.4064)
			(end 0.7874 -0.4064)
			(stroke
				(width 0.1524)
				(type default)
			)
			(layer "F.SilkS")
		)
		(fp_line
			(start 0.67945 0.3048)
			(end 0.120396 0.3048)
			(stroke
				(width 0.1)
				(type default)
			)
			(layer "F.Fab")
		)
		(fp_line
			(start 0.67945 -0.3048)
			(end 0.67945 0.3048)
			(stroke
				(width 0.1)
				(type default)
			)
			(layer "F.Fab")
		)
		(fp_line
			(start 0.12065 -0.2794)
			(end 0.12065 -0.3048)
			(stroke
				(width 0.1)
				(type default)
			)
			(layer "F.Fab")
		)
		(fp_line
			(start 0.12065 -0.3048)
			(end 0.67945 -0.3048)
			(stroke
				(width 0.1)
				(type default)
			)
			(layer "F.Fab")
		)
		(fp_line
			(start 0.120396 0.3048)
			(end 0.120396 0.2794)
			(stroke
				(width 0.1)
				(type default)
			)
			(layer "F.Fab")
		)
		(fp_line
			(start 0.120396 0.2794)
			(end -0.12065 0.2794)
			(stroke
				(width 0.1)
				(type default)
			)
			(layer "F.Fab")
		)
		(fp_line
			(start -0.12065 0.3048)
			(end -0.67945 0.3048)
			(stroke
				(width 0.1)
				(type default)
			)
			(layer "F.Fab")
		)
		(fp_line
			(start -0.12065 0.2794)
			(end -0.12065 0.3048)
			(stroke
				(width 0.1)
				(type default)
			)
			(layer "F.Fab")
		)
		(fp_line
			(start -0.12065 -0.2794)
			(end 0.12065 -0.2794)
			(stroke
				(width 0.1)
				(type default)
			)
			(layer "F.Fab")
		)
		(fp_line
			(start -0.12065 -0.305054)
			(end -0.12065 -0.2794)
			(stroke
				(width 0.1)
				(type default)
			)
			(layer "F.Fab")
		)
		(fp_line
			(start -0.67945 0.3048)
			(end -0.67945 -0.305054)
			(stroke
				(width 0.1)
				(type default)
			)
			(layer "F.Fab")
		)
		(fp_line
			(start -0.67945 -0.305054)
			(end -0.12065 -0.305054)
			(stroke
				(width 0.1)
				(type default)
			)
			(layer "F.Fab")
		)
		(pad "1" smd circle
			(at -0.40005 0 180)
			(size 0 0)
			(layers "F.Cu" "F.Mask" "F.Paste")
			(net "FM_PVCCFA_EHV_CPU0_EN")
		)
		(pad "2" smd circle
			(at 0.40005 0 180)
			(size 0 0)
			(layers "F.Cu" "F.Mask" "F.Paste")
			(net "PVCCFA_EHV_CPU0_EN_R")
		)
	)
)
